(kicad_pcb
	(version 20260206)
	(generator "pcbnew")
	(generator_version "10.0")
	(general
		(thickness 1.6)
		(legacy_teardrops no)
	)
	(paper "A4")
	(title_block
		(title "Wiwynn_Tioga_Pass_MB.brd")
		(comment 1 "Tioga Pass / footprints 2213-2220 of 4770")
	)
	(layers
		(0 "F.Cu" signal "TOP")
		(4 "In1.Cu" signal "L2GND")
		(6 "In2.Cu" signal "L3")
		(8 "In3.Cu" signal "L4GND")
		(10 "In4.Cu" signal "L5")
		(12 "In5.Cu" signal "L6GND")
		(14 "In6.Cu" signal "L7VCC")
		(16 "In7.Cu" signal "L8VCC")
		(18 "In8.Cu" signal "L9GND")
		(20 "In9.Cu" signal "L10")
		(22 "In10.Cu" signal "L11GND")
		(24 "In11.Cu" signal "L12")
		(26 "In12.Cu" signal "L13GND")
		(2 "B.Cu" signal "BOTTOM")
		(9 "F.Adhes" user "F.Adhesive")
		(11 "B.Adhes" user "B.Adhesive")
		(13 "F.Paste" user "Package Geometry/Pastemask Top")
		(15 "B.Paste" user "Package Geometry/Pastemask Bottom")
		(5 "F.SilkS" user "Ref Des/Silkscreen Top")
		(7 "B.SilkS" user "Ref Des/Silkscreen Bottom")
		(1 "F.Mask" user "Board Geometry/Soldermask Top")
		(3 "B.Mask" user "Board Geometry/Soldermask Bottom")
		(17 "Dwgs.User" user "User.Drawings")
		(19 "Cmts.User" user "User.Comments")
		(21 "Eco1.User" user "User.Eco1")
		(23 "Eco2.User" user "User.Eco2")
		(25 "Edge.Cuts" user "Board Geometry/Outline")
		(27 "Margin" user)
		(31 "F.CrtYd" user "Package Geometry/Place Bound Top")
		(29 "B.CrtYd" user "Package Geometry/Place Bound Bottom")
		(35 "F.Fab" user "Ref Des/Assembly Top")
		(33 "B.Fab" user "Ref Des/Assembly Bottom")
	)
	(footprint ""
		(layer "F.Cu")
		(at 163.576 -79.248 -90)
		(property "Reference" "R4D21"
			(at 0 0 270)
			(layer "F.SilkS")
			(hide yes)
			(effects
				(font
					(size 1.27 1.27)
				)
			)
		)
		(property "Value" ""
			(at 0 0 270)
			(layer "F.Fab")
			(effects
				(font
					(size 1.27 1.27)
				)
			)
		)
		(duplicate_pad_numbers_are_jumpers no)
		(fp_poly
			(pts
				(xy -0.2794 -0.1016) (xy 0.2794 -0.1016) (xy 0.2794 0.9906) (xy -0.2794 0.9906)
			)
			(stroke
				(width 0)
				(type default)
			)
			(fill no)
			(layer "F.CrtYd")
		)
		(fp_line
			(start -0.2794 0.9906)
			(end 0.2794 0.9906)
			(stroke
				(width 0.1)
				(type default)
			)
			(layer "F.Fab")
		)
		(fp_line
			(start 0.2794 0.9906)
			(end 0.2794 -0.1016)
			(stroke
				(width 0.1)
				(type default)
			)
			(layer "F.Fab")
		)
		(fp_line
			(start -0.2794 -0.1016)
			(end -0.2794 0.9906)
			(stroke
				(width 0.1)
				(type default)
			)
			(layer "F.Fab")
		)
		(fp_line
			(start 0.2794 -0.1016)
			(end -0.2794 -0.1016)
			(stroke
				(width 0.1)
				(type default)
			)
			(layer "F.Fab")
		)
		(pad "1" smd rect
			(at 0 0 270)
			(size 0.508 0.508)
			(layers "F.Cu" "F.Mask" "F.Paste")
			(net "CLK_100M_CPU1_RC_REFCLK0_R_DN")
		)
		(pad "2" smd rect
			(at 0 0.889 270)
			(size 0.508 0.508)
			(layers "F.Cu" "F.Mask" "F.Paste")
			(net "CLK_100M_CPU1_RC_REFCLK0_DN")
		)
		(zone
			(layer "F.Cu")
			(hatch none 0.5)
			(connect_pads
				(clearance 0)
			)
			(min_thickness 0.25)
			(keepout
				(tracks not_allowed)
				(vias allowed)
				(pads allowed)
				(copperpour not_allowed)
				(footprints allowed)
			)
			(placement
				(enabled no)
				(sheetname "")
			)
			(fill
				(thermal_gap 0.5)
				(thermal_bridge_width 0.5)
				(island_removal_mode 0)
			)
			(polygon
				(pts
					(xy 162.941 -79.502) (xy 162.941 -78.994) (xy 163.322 -78.994) (xy 163.322 -79.502)
				)
			)
		)
		(zone
			(layer "F.Cu")
			(hatch none 0.5)
			(connect_pads
				(clearance 0)
			)
			(min_thickness 0.25)
			(keepout
				(tracks allowed)
				(vias not_allowed)
				(pads allowed)
				(copperpour not_allowed)
				(footprints allowed)
			)
			(placement
				(enabled no)
				(sheetname "")
			)
			(fill
				(thermal_gap 0.5)
				(thermal_bridge_width 0.5)
				(island_removal_mode 0)
			)
			(polygon
				(pts
					(xy 163.322 -79.502) (xy 163.322 -78.994) (xy 162.941 -78.994) (xy 162.941 -79.502)
				)
			)
		)
	)
	(footprint ""
		(layer "F.Cu")
		(at 197.066154 -61.205364 -90)
		(property "Reference" "C4E26"
			(at 0 0 270)
			(layer "F.SilkS")
			(hide yes)
			(effects
				(font
					(size 1.27 1.27)
				)
			)
		)
		(property "Value" ""
			(at 0 0 270)
			(layer "F.Fab")
			(effects
				(font
					(size 1.27 1.27)
				)
			)
		)
		(duplicate_pad_numbers_are_jumpers no)
		(fp_poly
			(pts
				(xy 0.3048 -0.1016) (xy 0.3048 0.9906) (xy -0.3048 0.9906) (xy -0.3048 -0.1016)
			)
			(stroke
				(width 0)
				(type default)
			)
			(fill no)
			(layer "F.CrtYd")
		)
		(fp_line
			(start -0.3048 0.9906)
			(end 0.3048 0.9906)
			(stroke
				(width 0.1)
				(type default)
			)
			(layer "F.Fab")
		)
		(fp_line
			(start 0.3048 0.9906)
			(end 0.3048 -0.1016)
			(stroke
				(width 0.1)
				(type default)
			)
			(layer "F.Fab")
		)
		(fp_line
			(start -0.3048 -0.1016)
			(end -0.3048 0.9906)
			(stroke
				(width 0.1)
				(type default)
			)
			(layer "F.Fab")
		)
		(fp_line
			(start 0.3048 -0.1016)
			(end -0.3048 -0.1016)
			(stroke
				(width 0.1)
				(type default)
			)
			(layer "F.Fab")
		)
		(pad "1" smd rect
			(at 0 0 270)
			(size 0.508 0.508)
			(layers "F.Cu" "F.Mask" "F.Paste")
			(net "VR_PVCCIN_CPU0_PH2_VCIN")
		)
		(pad "2" smd rect
			(at 0 0.889 270)
			(size 0.508 0.508)
			(layers "F.Cu" "F.Mask" "F.Paste")
			(net "GND")
		)
		(zone
			(layer "F.Cu")
			(hatch none 0.5)
			(connect_pads
				(clearance 0)
			)
			(min_thickness 0.25)
			(keepout
				(tracks not_allowed)
				(vias allowed)
				(pads allowed)
				(copperpour not_allowed)
				(footprints allowed)
			)
			(placement
				(enabled no)
				(sheetname "")
			)
			(fill
				(thermal_gap 0.5)
				(thermal_bridge_width 0.5)
				(island_removal_mode 0)
			)
			(polygon
				(pts
					(xy 196.431154 -61.459364) (xy 196.431154 -60.951364) (xy 196.812154 -60.951364) (xy 196.812154 -61.459364)
				)
			)
		)
		(zone
			(layer "F.Cu")
			(hatch none 0.5)
			(connect_pads
				(clearance 0)
			)
			(min_thickness 0.25)
			(keepout
				(tracks allowed)
				(vias not_allowed)
				(pads allowed)
				(copperpour not_allowed)
				(footprints allowed)
			)
			(placement
				(enabled no)
				(sheetname "")
			)
			(fill
				(thermal_gap 0.5)
				(thermal_bridge_width 0.5)
				(island_removal_mode 0)
			)
			(polygon
				(pts
					(xy 196.812154 -61.459364) (xy 196.812154 -60.951364) (xy 196.431154 -60.951364) (xy 196.431154 -61.459364)
				)
			)
		)
	)
	(footprint ""
		(layer "F.Cu")
		(at 6.0452 -130.302 180)
		(property "Reference" "C1B5"
			(at -0.8382 -0.67818 180)
			(unlocked yes)
			(layer "F.SilkS")
			(effects
				(font
					(size 0.4064 0.254)
					(thickness 0.1524)
				)
				(justify left)
			)
		)
		(property "Value" ""
			(at 0 0 180)
			(layer "F.Fab")
			(effects
				(font
					(size 1.27 1.27)
				)
			)
		)
		(duplicate_pad_numbers_are_jumpers no)
		(fp_poly
			(pts
				(xy 0.3048 -0.1016) (xy 0.3048 0.9906) (xy -0.3048 0.9906) (xy -0.3048 -0.1016)
			)
			(stroke
				(width 0)
				(type default)
			)
			(fill no)
			(layer "F.CrtYd")
		)
		(fp_line
			(start 0.3048 0.9906)
			(end 0.3048 -0.1016)
			(stroke
				(width 0.1)
				(type default)
			)
			(layer "F.Fab")
		)
		(fp_line
			(start 0.3048 -0.1016)
			(end -0.3048 -0.1016)
			(stroke
				(width 0.1)
				(type default)
			)
			(layer "F.Fab")
		)
		(fp_line
			(start -0.3048 0.9906)
			(end 0.3048 0.9906)
			(stroke
				(width 0.1)
				(type default)
			)
			(layer "F.Fab")
		)
		(fp_line
			(start -0.3048 -0.1016)
			(end -0.3048 0.9906)
			(stroke
				(width 0.1)
				(type default)
			)
			(layer "F.Fab")
		)
		(pad "1" smd rect
			(at 0 0 180)
			(size 0.508 0.508)
			(layers "F.Cu" "F.Mask" "F.Paste")
			(net "VR_PVDDQ_KLM_VDD")
		)
		(pad "2" smd rect
			(at 0 0.889 180)
			(size 0.508 0.508)
			(layers "F.Cu" "F.Mask" "F.Paste")
			(net "GND")
		)
		(zone
			(layer "F.Cu")
			(hatch none 0.5)
			(connect_pads
				(clearance 0)
			)
			(min_thickness 0.25)
			(keepout
				(tracks not_allowed)
				(vias allowed)
				(pads allowed)
				(copperpour not_allowed)
				(footprints allowed)
			)
			(placement
				(enabled no)
				(sheetname "")
			)
			(fill
				(thermal_gap 0.5)
				(thermal_bridge_width 0.5)
				(island_removal_mode 0)
			)
			(polygon
				(pts
					(xy 6.2992 -130.937) (xy 5.7912 -130.937) (xy 5.7912 -130.556) (xy 6.2992 -130.556)
				)
			)
		)
		(zone
			(layer "F.Cu")
			(hatch none 0.5)
			(connect_pads
				(clearance 0)
			)
			(min_thickness 0.25)
			(keepout
				(tracks allowed)
				(vias not_allowed)
				(pads allowed)
				(copperpour not_allowed)
				(footprints allowed)
			)
			(placement
				(enabled no)
				(sheetname "")
			)
			(fill
				(thermal_gap 0.5)
				(thermal_bridge_width 0.5)
				(island_removal_mode 0)
			)
			(polygon
				(pts
					(xy 6.2992 -130.556) (xy 5.7912 -130.556) (xy 5.7912 -130.937) (xy 6.2992 -130.937)
				)
			)
		)
	)
	(footprint ""
		(layer "F.Cu")
		(at 2.032 -75.057 180)
		(property "Reference" "R9R8"
			(at 0 0 180)
			(layer "F.SilkS")
			(hide yes)
			(effects
				(font
					(size 1.27 1.27)
				)
			)
		)
		(property "Value" ""
			(at 0 0 180)
			(layer "F.Fab")
			(effects
				(font
					(size 1.27 1.27)
				)
			)
		)
		(duplicate_pad_numbers_are_jumpers no)
		(fp_poly
			(pts
				(xy -0.2794 -0.1016) (xy 0.2794 -0.1016) (xy 0.2794 0.9906) (xy -0.2794 0.9906)
			)
			(stroke
				(width 0)
				(type default)
			)
			(fill no)
			(layer "F.CrtYd")
		)
		(fp_line
			(start 0.2794 0.9906)
			(end 0.2794 -0.1016)
			(stroke
				(width 0.1)
				(type default)
			)
			(layer "F.Fab")
		)
		(fp_line
			(start 0.2794 -0.1016)
			(end -0.2794 -0.1016)
			(stroke
				(width 0.1)
				(type default)
			)
			(layer "F.Fab")
		)
		(fp_line
			(start -0.2794 0.9906)
			(end 0.2794 0.9906)
			(stroke
				(width 0.1)
				(type default)
			)
			(layer "F.Fab")
		)
		(fp_line
			(start -0.2794 -0.1016)
			(end -0.2794 0.9906)
			(stroke
				(width 0.1)
				(type default)
			)
			(layer "F.Fab")
		)
		(pad "1" smd rect
			(at 0 0 180)
			(size 0.508 0.508)
			(layers "F.Cu" "F.Mask" "F.Paste")
			(net "SMB_SENSOR_TMP421_2_SDA")
		)
		(pad "2" smd rect
			(at 0 0.889 180)
			(size 0.508 0.508)
			(layers "F.Cu" "F.Mask" "F.Paste")
			(net "SMB_SENSOR_STBY_LVC3_SDA")
		)
		(zone
			(layer "F.Cu")
			(hatch none 0.5)
			(connect_pads
				(clearance 0)
			)
			(min_thickness 0.25)
			(keepout
				(tracks not_allowed)
				(vias allowed)
				(pads allowed)
				(copperpour not_allowed)
				(footprints allowed)
			)
			(placement
				(enabled no)
				(sheetname "")
			)
			(fill
				(thermal_gap 0.5)
				(thermal_bridge_width 0.5)
				(island_removal_mode 0)
			)
			(polygon
				(pts
					(xy 2.286 -75.692) (xy 1.778 -75.692) (xy 1.778 -75.311) (xy 2.286 -75.311)
				)
			)
		)
		(zone
			(layer "F.Cu")
			(hatch none 0.5)
			(connect_pads
				(clearance 0)
			)
			(min_thickness 0.25)
			(keepout
				(tracks allowed)
				(vias not_allowed)
				(pads allowed)
				(copperpour not_allowed)
				(footprints allowed)
			)
			(placement
				(enabled no)
				(sheetname "")
			)
			(fill
				(thermal_gap 0.5)
				(thermal_bridge_width 0.5)
				(island_removal_mode 0)
			)
			(polygon
				(pts
					(xy 2.286 -75.311) (xy 1.778 -75.311) (xy 1.778 -75.692) (xy 2.286 -75.692)
				)
			)
		)
	)
	(footprint ""
		(layer "F.Cu")
		(at 38.91534 -61.090048 -90)
		(property "Reference" "CT27"
			(at -0.8382 -0.67818 270)
			(unlocked yes)
			(layer "F.SilkS")
			(effects
				(font
					(size 0.4064 0.254)
					(thickness 0.1524)
				)
				(justify left)
			)
		)
		(property "Value" ""
			(at 0 0 270)
			(layer "F.Fab")
			(effects
				(font
					(size 1.27 1.27)
				)
			)
		)
		(duplicate_pad_numbers_are_jumpers no)
		(fp_poly
			(pts
				(xy 0.3048 -0.1016) (xy 0.3048 0.9906) (xy -0.3048 0.9906) (xy -0.3048 -0.1016)
			)
			(stroke
				(width 0)
				(type default)
			)
			(fill no)
			(layer "F.CrtYd")
		)
		(fp_line
			(start -0.3048 0.9906)
			(end 0.3048 0.9906)
			(stroke
				(width 0.1)
				(type default)
			)
			(layer "F.Fab")
		)
		(fp_line
			(start 0.3048 0.9906)
			(end 0.3048 -0.1016)
			(stroke
				(width 0.1)
				(type default)
			)
			(layer "F.Fab")
		)
		(fp_line
			(start -0.3048 -0.1016)
			(end -0.3048 0.9906)
			(stroke
				(width 0.1)
				(type default)
			)
			(layer "F.Fab")
		)
		(fp_line
			(start 0.3048 -0.1016)
			(end -0.3048 -0.1016)
			(stroke
				(width 0.1)
				(type default)
			)
			(layer "F.Fab")
		)
		(pad "1" smd rect
			(at 0 0 270)
			(size 0.508 0.508)
			(layers "F.Cu" "F.Mask" "F.Paste")
			(net "VR_PVCCIN_CPU1_PHASE2")
		)
		(pad "2" smd rect
			(at 0 0.889 270)
			(size 0.508 0.508)
			(layers "F.Cu" "F.Mask" "F.Paste")
			(net "VR_PVCCIN_CPU1_PHASE2_RC")
		)
		(zone
			(layer "F.Cu")
			(hatch none 0.5)
			(connect_pads
				(clearance 0)
			)
			(min_thickness 0.25)
			(keepout
				(tracks not_allowed)
				(vias allowed)
				(pads allowed)
				(copperpour not_allowed)
				(footprints allowed)
			)
			(placement
				(enabled no)
				(sheetname "")
			)
			(fill
				(thermal_gap 0.5)
				(thermal_bridge_width 0.5)
				(island_removal_mode 0)
			)
			(polygon
				(pts
					(xy 38.28034 -61.344048) (xy 38.28034 -60.836048) (xy 38.66134 -60.836048) (xy 38.66134 -61.344048)
				)
			)
		)
		(zone
			(layer "F.Cu")
			(hatch none 0.5)
			(connect_pads
				(clearance 0)
			)
			(min_thickness 0.25)
			(keepout
				(tracks allowed)
				(vias not_allowed)
				(pads allowed)
				(copperpour not_allowed)
				(footprints allowed)
			)
			(placement
				(enabled no)
				(sheetname "")
			)
			(fill
				(thermal_gap 0.5)
				(thermal_bridge_width 0.5)
				(island_removal_mode 0)
			)
			(polygon
				(pts
					(xy 38.66134 -61.344048) (xy 38.66134 -60.836048) (xy 38.28034 -60.836048) (xy 38.28034 -61.344048)
				)
			)
		)
	)
	(footprint ""
		(layer "F.Cu")
		(at 342.802464 -11.013694 90)
		(property "Reference" "CF15"
			(at 0 0 90)
			(layer "F.SilkS")
			(hide yes)
			(effects
				(font
					(size 1.27 1.27)
				)
			)
		)
		(property "Value" "*"
			(at 1.1811 -2.8194 90)
			(unlocked yes)
			(layer "F.Fab")
			(hide yes)
			(effects
				(font
					(size 1.27 1.016)
					(thickness 0.1524)
				)
			)
		)
		(property "Device Type" "SC22P50V2JN-4GP_SMD-BCG-SC22P5A"
			(at 1.1811 -4.3434 90)
			(unlocked yes)
			(layer "F.Fab")
			(hide yes)
			(effects
				(font
					(size 1.27 1.016)
					(thickness 0.1524)
				)
			)
		)
		(duplicate_pad_numbers_are_jumpers no)
		(fp_rect
			(start -0.4318 0.9525)
			(end 0.4318 -0.9525)
			(stroke
				(width 0)
				(type default)
			)
			(fill no)
			(layer "F.CrtYd")
		)
		(fp_rect
			(start -0.4318 0.9525)
			(end 0.4318 -0.9525)
			(stroke
				(width 0)
				(type default)
			)
			(fill no)
			(layer "F.Fab")
		)
		(pad "1" smd custom
			(at 0 -0.4445 90)
			(size 0.1524 0.1524)
			(layers "F.Cu" "F.Mask" "F.Paste")
			(net "VR_PVDDQ_ABC_AIREF1")
			(options
				(clearance outline)
				(anchor circle)
			)
			(primitives
				(gr_poly
					(pts
						(arc
							(start 0.3048 -0.2032)
							(mid 0.275042 -0.275042)
							(end 0.2032 -0.3048)
						)
						(arc
							(start -0.2032 -0.3048)
							(mid -0.275042 -0.275042)
							(end -0.3048 -0.2032)
						)
						(arc
							(start -0.3048 0.2032)
							(mid -0.275042 0.275042)
							(end -0.2032 0.3048)
						)
						(arc
							(start 0.2032 0.3048)
							(mid 0.275042 0.275042)
							(end 0.3048 0.2032)
						)
					)
					(width 0)
					(fill yes)
				)
			)
		)
		(pad "2" smd custom
			(at 0 0.4445 90)
			(size 0.1524 0.1524)
			(layers "F.Cu" "F.Mask" "F.Paste")
			(net "ISENSE_PVDDQ_ABC_PH1_IMON")
			(options
				(clearance outline)
				(anchor circle)
			)
			(primitives
				(gr_poly
					(pts
						(arc
							(start 0.3048 -0.2032)
							(mid 0.275042 -0.275042)
							(end 0.2032 -0.3048)
						)
						(arc
							(start -0.2032 -0.3048)
							(mid -0.275042 -0.275042)
							(end -0.3048 -0.2032)
						)
						(arc
							(start -0.3048 0.2032)
							(mid -0.275042 0.275042)
							(end -0.2032 0.3048)
						)
						(arc
							(start 0.2032 0.3048)
							(mid 0.275042 0.275042)
							(end 0.3048 0.2032)
						)
					)
					(width 0)
					(fill yes)
				)
			)
		)
	)
	(footprint ""
		(layer "F.Cu")
		(at 108.48721 -84.890102)
		(property "Reference" "C3D2"
			(at 0 0 0)
			(layer "F.SilkS")
			(hide yes)
			(effects
				(font
					(size 1.27 1.27)
				)
			)
		)
		(property "Value" ""
			(at 0 0 0)
			(layer "F.Fab")
			(effects
				(font
					(size 1.27 1.27)
				)
			)
		)
		(duplicate_pad_numbers_are_jumpers no)
		(fp_poly
			(pts
				(xy -0.4953 -0.2032) (xy 0.4953 -0.2032) (xy 0.4953 1.6002) (xy -0.4953 1.6002)
			)
			(stroke
				(width 0)
				(type default)
			)
			(fill no)
			(layer "F.CrtYd")
		)
		(fp_line
			(start -0.4953 -0.2032)
			(end 0.4953 -0.2032)
			(stroke
				(width 0.1)
				(type default)
			)
			(layer "F.Fab")
		)
		(fp_line
			(start -0.4953 1.6002)
			(end -0.4953 -0.2032)
			(stroke
				(width 0.1)
				(type default)
			)
			(layer "F.Fab")
		)
		(fp_line
			(start 0.4953 -0.2032)
			(end 0.4953 1.6002)
			(stroke
				(width 0.1)
				(type default)
			)
			(layer "F.Fab")
		)
		(fp_line
			(start 0.4953 1.6002)
			(end -0.4953 1.6002)
			(stroke
				(width 0.1)
				(type default)
			)
			(layer "F.Fab")
		)
		(pad "1" smd rect
			(at 0 0)
			(size 0.762 0.889)
			(layers "F.Cu" "F.Mask" "F.Paste")
			(net "PVCCIN_CPU1")
		)
		(pad "2" smd rect
			(at 0 1.397)
			(size 0.762 0.889)
			(layers "F.Cu" "F.Mask" "F.Paste")
			(net "GND")
		)
		(zone
			(layer "F.Cu")
			(hatch none 0.5)
			(connect_pads
				(clearance 0)
			)
			(min_thickness 0.25)
			(keepout
				(tracks not_allowed)
				(vias allowed)
				(pads allowed)
				(copperpour not_allowed)
				(footprints allowed)
			)
			(placement
				(enabled no)
				(sheetname "")
			)
			(fill
				(thermal_gap 0.5)
				(thermal_bridge_width 0.5)
				(island_removal_mode 0)
			)
			(polygon
				(pts
					(xy 108.10621 -84.445602) (xy 108.86821 -84.445602) (xy 108.86821 -83.937602) (xy 108.10621 -83.937602)
				)
			)
		)
	)
	(footprint ""
		(layer "F.Cu")
		(at 111.97844 -73.318116)
		(property "Reference" "C3D20"
			(at 0 0 0)
			(layer "F.SilkS")
			(hide yes)
			(effects
				(font
					(size 1.27 1.27)
				)
			)
		)
		(property "Value" ""
			(at 0 0 0)
			(layer "F.Fab")
			(effects
				(font
					(size 1.27 1.27)
				)
			)
		)
		(duplicate_pad_numbers_are_jumpers no)
		(fp_poly
			(pts
				(xy -0.4953 -0.2032) (xy 0.4953 -0.2032) (xy 0.4953 1.6002) (xy -0.4953 1.6002)
			)
			(stroke
				(width 0)
				(type default)
			)
			(fill no)
			(layer "F.CrtYd")
		)
		(fp_line
			(start -0.4953 -0.2032)
			(end 0.4953 -0.2032)
			(stroke
				(width 0.1)
				(type default)
			)
			(layer "F.Fab")
		)
		(fp_line
			(start -0.4953 1.6002)
			(end -0.4953 -0.2032)
			(stroke
				(width 0.1)
				(type default)
			)
			(layer "F.Fab")
		)
		(fp_line
			(start 0.4953 -0.2032)
			(end 0.4953 1.6002)
			(stroke
				(width 0.1)
				(type default)
			)
			(layer "F.Fab")
		)
		(fp_line
			(start 0.4953 1.6002)
			(end -0.4953 1.6002)
			(stroke
				(width 0.1)
				(type default)
			)
			(layer "F.Fab")
		)
		(pad "1" smd rect
			(at 0 0)
			(size 0.762 0.889)
			(layers "F.Cu" "F.Mask" "F.Paste")
			(net "PVCCMCP_CPU1")
		)
		(pad "2" smd rect
			(at 0 1.397)
			(size 0.762 0.889)
			(layers "F.Cu" "F.Mask" "F.Paste")
			(net "GND")
		)
		(zone
			(layer "F.Cu")
			(hatch none 0.5)
			(connect_pads
				(clearance 0)
			)
			(min_thickness 0.25)
			(keepout
				(tracks not_allowed)
				(vias allowed)
				(pads allowed)
				(copperpour not_allowed)
				(footprints allowed)
			)
			(placement
				(enabled no)
				(sheetname "")
			)
			(fill
				(thermal_gap 0.5)
				(thermal_bridge_width 0.5)
				(island_removal_mode 0)
			)
			(polygon
				(pts
					(xy 111.59744 -72.873616) (xy 112.35944 -72.873616) (xy 112.35944 -72.365616) (xy 111.59744 -72.365616)
				)
			)
		)
	)
)
